(kicad_pcb
	(version 20241229)
	(generator "pcbnew")
	(generator_version "9.0")
	(general
		(thickness 1.599998)
		(legacy_teardrops no)
	)
	(paper "A4")
	(title_block
		(date "2023-02-12")
		(rev "1.1.5")
		(comment 9 "footprints 120-126 of 473")
	)
	(layers
		(0 "F.Cu" signal)
		(4 "In1.Cu" power "In1.GND")
		(6 "In2.Cu" signal)
		(8 "In3.Cu" power "In3.GND")
		(10 "In4.Cu" power "In4.VCC")
		(12 "In5.Cu" signal)
		(14 "In6.Cu" power "In6.VCC")
		(2 "B.Cu" signal)
		(9 "F.Adhes" user "F.Adhesive")
		(11 "B.Adhes" user "B.Adhesive")
		(13 "F.Paste" user)
		(15 "B.Paste" user)
		(5 "F.SilkS" user "F.Silkscreen")
		(7 "B.SilkS" user "B.Silkscreen")
		(1 "F.Mask" user)
		(3 "B.Mask" user)
		(17 "Dwgs.User" user "User.Drawings")
		(19 "Cmts.User" user "User.Comments")
		(21 "Eco1.User" user "User.Eco1")
		(23 "Eco2.User" user "User.Eco2")
		(25 "Edge.Cuts" user)
		(27 "Margin" user)
		(31 "F.CrtYd" user "F.Courtyard")
		(29 "B.CrtYd" user "B.Courtyard")
		(35 "F.Fab" user)
		(33 "B.Fab" user)
	)
	(footprint "antmicro-footprints:C_0402_1005Metric"
		(layer "F.Cu")
		(at 205.486328 106.174306 -90)
		(descr "Capacitor SMD 0402")
		(tags "capacitor SMD 0402")
		(property "Reference" "C108"
			(at 1.825694 -2.413672 270)
			(layer "F.SilkS")
			(effects
				(font
					(size 0.7 0.7)
					(thickness 0.15)
				)
				(justify left bottom)
			)
		)
		(property "Value" "C_470n_0402"
			(at 0 1.4 270)
			(layer "F.Fab")
			(effects
				(font
					(size 0.7 0.7)
					(thickness 0.15)
				)
				(justify left bottom)
			)
		)
		(property "Description" " "
			(at 0 0 270)
			(layer "F.Fab")
			(hide yes)
			(effects
				(font
					(size 1.27 1.27)
					(thickness 0.15)
				)
			)
		)
		(property "Author" "Antmicro"
			(at 99.312022 311.660634 0)
			(layer "F.Fab")
			(hide yes)
			(effects
				(font
					(size 1 1)
					(thickness 0.15)
				)
			)
		)
		(property "Dielectric" ""
			(at 99.312022 311.660634 0)
			(layer "F.Fab")
			(hide yes)
			(effects
				(font
					(size 1 1)
					(thickness 0.15)
				)
			)
		)
		(property "License" "Apache-2.0"
			(at 99.312022 311.660634 0)
			(layer "F.Fab")
			(hide yes)
			(effects
				(font
					(size 1 1)
					(thickness 0.15)
				)
			)
		)
		(property "MPN" "C1005X5R1E474M050BB"
			(at 99.312022 311.660634 0)
			(layer "F.Fab")
			(hide yes)
			(effects
				(font
					(size 1 1)
					(thickness 0.15)
				)
			)
		)
		(property "Manufacturer" "TDK"
			(at 99.312022 311.660634 0)
			(layer "F.Fab")
			(hide yes)
			(effects
				(font
					(size 1 1)
					(thickness 0.15)
				)
			)
		)
		(property "Val" "470n"
			(at 99.312022 311.660634 0)
			(layer "F.Fab")
			(hide yes)
			(effects
				(font
					(size 1 1)
					(thickness 0.15)
				)
			)
		)
		(property "Voltage" ""
			(at 99.312022 311.660634 0)
			(layer "F.Fab")
			(hide yes)
			(effects
				(font
					(size 1 1)
					(thickness 0.15)
				)
			)
		)
		(sheetname "Ethernet")
		(sheetfile "ethernet.kicad_sch")
		(attr smd)
		(fp_rect
			(start -0.94 -0.47)
			(end 0.94 0.47)
			(stroke
				(width 0.05)
				(type solid)
			)
			(fill no)
			(layer "F.CrtYd")
		)
		(fp_rect
			(start -0.499 -0.249)
			(end 0.499 0.249)
			(stroke
				(width 0.15)
				(type solid)
			)
			(fill no)
			(layer "F.Fab")
		)
		(pad "1" smd roundrect
			(at -0.484 0 270)
			(size 0.59 0.64)
			(layers "F.Cu" "F.Mask" "F.Paste")
			(roundrect_rratio 0.25)
			(net 602 "1V2_SYS")
			(pintype "passive")
		)
		(pad "2" smd roundrect
			(at 0.484 0 270)
			(size 0.59 0.64)
			(layers "F.Cu" "F.Mask" "F.Paste")
			(roundrect_rratio 0.25)
			(net 5 "GND")
			(pintype "passive")
		)
	)
	(footprint "antmicro-footprints:C_0402_1005Metric"
		(layer "F.Cu")
		(at 206.586328 100.374306 90)
		(descr "Capacitor SMD 0402")
		(tags "capacitor SMD 0402")
		(property "Reference" "C113"
			(at -1.425694 1.313672 90)
			(layer "F.SilkS")
			(effects
				(font
					(size 0.7 0.7)
					(thickness 0.15)
				)
				(justify left bottom)
			)
		)
		(property "Value" "C_10n_0402"
			(at 0 1.4 90)
			(layer "F.Fab")
			(effects
				(font
					(size 0.7 0.7)
					(thickness 0.15)
				)
				(justify left bottom)
			)
		)
		(property "Description" " "
			(at 0 0 90)
			(layer "F.Fab")
			(hide yes)
			(effects
				(font
					(size 1.27 1.27)
					(thickness 0.15)
				)
			)
		)
		(property "Author" "Antmicro"
			(at 306.960634 -106.212022 0)
			(layer "F.Fab")
			(hide yes)
			(effects
				(font
					(size 1 1)
					(thickness 0.15)
				)
			)
		)
		(property "Dielectric" "X7R"
			(at 306.960634 -106.212022 0)
			(layer "F.Fab")
			(hide yes)
			(effects
				(font
					(size 1 1)
					(thickness 0.15)
				)
			)
		)
		(property "License" "Apache-2.0"
			(at 306.960634 -106.212022 0)
			(layer "F.Fab")
			(hide yes)
			(effects
				(font
					(size 1 1)
					(thickness 0.15)
				)
			)
		)
		(property "MPN" "GRM155R71H103KA88D"
			(at 306.960634 -106.212022 0)
			(layer "F.Fab")
			(hide yes)
			(effects
				(font
					(size 1 1)
					(thickness 0.15)
				)
			)
		)
		(property "Manufacturer" "Murata"
			(at 306.960634 -106.212022 0)
			(layer "F.Fab")
			(hide yes)
			(effects
				(font
					(size 1 1)
					(thickness 0.15)
				)
			)
		)
		(property "Val" "10n"
			(at 306.960634 -106.212022 0)
			(layer "F.Fab")
			(hide yes)
			(effects
				(font
					(size 1 1)
					(thickness 0.15)
				)
			)
		)
		(property "Voltage" "50V"
			(at 306.960634 -106.212022 0)
			(layer "F.Fab")
			(hide yes)
			(effects
				(font
					(size 1 1)
					(thickness 0.15)
				)
			)
		)
		(sheetname "Ethernet")
		(sheetfile "ethernet.kicad_sch")
		(attr smd)
		(fp_rect
			(start -0.94 -0.47)
			(end 0.94 0.47)
			(stroke
				(width 0.05)
				(type solid)
			)
			(fill no)
			(layer "F.CrtYd")
		)
		(fp_rect
			(start -0.499 -0.249)
			(end 0.499 0.249)
			(stroke
				(width 0.15)
				(type solid)
			)
			(fill no)
			(layer "F.Fab")
		)
		(pad "1" smd roundrect
			(at -0.484 0 90)
			(size 0.59 0.64)
			(layers "F.Cu" "F.Mask" "F.Paste")
			(roundrect_rratio 0.25)
			(net 602 "1V2_SYS")
			(pintype "passive")
		)
		(pad "2" smd roundrect
			(at 0.484 0 90)
			(size 0.59 0.64)
			(layers "F.Cu" "F.Mask" "F.Paste")
			(roundrect_rratio 0.25)
			(net 5 "GND")
			(pintype "passive")
		)
	)
	(footprint "antmicro-footprints:C_0402_1005Metric"
		(layer "F.Cu")
		(at 206.586328 106.174306 -90)
		(descr "Capacitor SMD 0402")
		(tags "capacitor SMD 0402")
		(property "Reference" "C120"
			(at 1.825694 -2.413672 270)
			(layer "F.SilkS")
			(effects
				(font
					(size 0.7 0.7)
					(thickness 0.15)
				)
				(justify left bottom)
			)
		)
		(property "Value" "C_10n_0402"
			(at 0 1.4 270)
			(layer "F.Fab")
			(effects
				(font
					(size 0.7 0.7)
					(thickness 0.15)
				)
				(justify left bottom)
			)
		)
		(property "Description" " "
			(at 0 0 270)
			(layer "F.Fab")
			(hide yes)
			(effects
				(font
					(size 1.27 1.27)
					(thickness 0.15)
				)
			)
		)
		(property "Author" "Antmicro"
			(at 100.412022 312.760634 0)
			(layer "F.Fab")
			(hide yes)
			(effects
				(font
					(size 1 1)
					(thickness 0.15)
				)
			)
		)
		(property "Dielectric" "X7R"
			(at 100.412022 312.760634 0)
			(layer "F.Fab")
			(hide yes)
			(effects
				(font
					(size 1 1)
					(thickness 0.15)
				)
			)
		)
		(property "License" "Apache-2.0"
			(at 100.412022 312.760634 0)
			(layer "F.Fab")
			(hide yes)
			(effects
				(font
					(size 1 1)
					(thickness 0.15)
				)
			)
		)
		(property "MPN" "GRM155R71H103KA88D"
			(at 100.412022 312.760634 0)
			(layer "F.Fab")
			(hide yes)
			(effects
				(font
					(size 1 1)
					(thickness 0.15)
				)
			)
		)
		(property "Manufacturer" "Murata"
			(at 100.412022 312.760634 0)
			(layer "F.Fab")
			(hide yes)
			(effects
				(font
					(size 1 1)
					(thickness 0.15)
				)
			)
		)
		(property "Val" "10n"
			(at 100.412022 312.760634 0)
			(layer "F.Fab")
			(hide yes)
			(effects
				(font
					(size 1 1)
					(thickness 0.15)
				)
			)
		)
		(property "Voltage" "50V"
			(at 100.412022 312.760634 0)
			(layer "F.Fab")
			(hide yes)
			(effects
				(font
					(size 1 1)
					(thickness 0.15)
				)
			)
		)
		(sheetname "Ethernet")
		(sheetfile "ethernet.kicad_sch")
		(attr smd)
		(fp_rect
			(start -0.94 -0.47)
			(end 0.94 0.47)
			(stroke
				(width 0.05)
				(type solid)
			)
			(fill no)
			(layer "F.CrtYd")
		)
		(fp_rect
			(start -0.499 -0.249)
			(end 0.499 0.249)
			(stroke
				(width 0.15)
				(type solid)
			)
			(fill no)
			(layer "F.Fab")
		)
		(pad "1" smd roundrect
			(at -0.484 0 270)
			(size 0.59 0.64)
			(layers "F.Cu" "F.Mask" "F.Paste")
			(roundrect_rratio 0.25)
			(net 602 "1V2_SYS")
			(pintype "passive")
		)
		(pad "2" smd roundrect
			(at 0.484 0 270)
			(size 0.59 0.64)
			(layers "F.Cu" "F.Mask" "F.Paste")
			(roundrect_rratio 0.25)
			(net 5 "GND")
			(pintype "passive")
		)
	)
	(footprint "antmicro-footprints:C_0402_1005Metric"
		(layer "F.Cu")
		(at 191.186328 102.874306 180)
		(descr "Capacitor SMD 0402")
		(tags "capacitor SMD 0402")
		(property "Reference" "C121"
			(at 3.486328 -0.525694 180)
			(layer "F.SilkS")
			(effects
				(font
					(size 0.7 0.7)
					(thickness 0.15)
				)
				(justify left bottom)
			)
		)
		(property "Value" "C_22p_0402"
			(at 0 1.4 180)
			(layer "F.Fab")
			(effects
				(font
					(size 0.7 0.7)
					(thickness 0.15)
				)
				(justify left bottom)
			)
		)
		(property "Description" " "
			(at 0 0 180)
			(layer "F.Fab")
			(hide yes)
			(effects
				(font
					(size 1.27 1.27)
					(thickness 0.15)
				)
			)
		)
		(property "Author" "Antmicro"
			(at 382.372656 205.748612 0)
			(layer "F.Fab")
			(hide yes)
			(effects
				(font
					(size 1 1)
					(thickness 0.15)
				)
			)
		)
		(property "Dielectric" ""
			(at 382.372656 205.748612 0)
			(layer "F.Fab")
			(hide yes)
			(effects
				(font
					(size 1 1)
					(thickness 0.15)
				)
			)
		)
		(property "License" "Apache-2.0"
			(at 382.372656 205.748612 0)
			(layer "F.Fab")
			(hide yes)
			(effects
				(font
					(size 1 1)
					(thickness 0.15)
				)
			)
		)
		(property "MPN" "CC0402JRNPO9BN220"
			(at 382.372656 205.748612 0)
			(layer "F.Fab")
			(hide yes)
			(effects
				(font
					(size 1 1)
					(thickness 0.15)
				)
			)
		)
		(property "Manufacturer" "Yaego"
			(at 382.372656 205.748612 0)
			(layer "F.Fab")
			(hide yes)
			(effects
				(font
					(size 1 1)
					(thickness 0.15)
				)
			)
		)
		(property "Val" "22p"
			(at 382.372656 205.748612 0)
			(layer "F.Fab")
			(hide yes)
			(effects
				(font
					(size 1 1)
					(thickness 0.15)
				)
			)
		)
		(property "Voltage" ""
			(at 382.372656 205.748612 0)
			(layer "F.Fab")
			(hide yes)
			(effects
				(font
					(size 1 1)
					(thickness 0.15)
				)
			)
		)
		(sheetname "Ethernet")
		(sheetfile "ethernet.kicad_sch")
		(attr smd)
		(fp_rect
			(start -0.94 -0.47)
			(end 0.94 0.47)
			(stroke
				(width 0.05)
				(type solid)
			)
			(fill no)
			(layer "F.CrtYd")
		)
		(fp_rect
			(start -0.499 -0.249)
			(end 0.499 0.249)
			(stroke
				(width 0.15)
				(type solid)
			)
			(fill no)
			(layer "F.Fab")
		)
		(pad "1" smd roundrect
			(at -0.484 0 180)
			(size 0.59 0.64)
			(layers "F.Cu" "F.Mask" "F.Paste")
			(roundrect_rratio 0.25)
			(net 656 "ETH_XO")
			(pintype "passive")
		)
		(pad "2" smd roundrect
			(at 0.484 0 180)
			(size 0.59 0.64)
			(layers "F.Cu" "F.Mask" "F.Paste")
			(roundrect_rratio 0.25)
			(net 5 "GND")
			(pintype "passive")
		)
	)
	(footprint "antmicro-footprints:C_0402_1005Metric"
		(layer "F.Cu")
		(at 189.986328 107.674306)
		(descr "Capacitor SMD 0402")
		(tags "capacitor SMD 0402")
		(property "Reference" "C122"
			(at -3.586328 0.325694 0)
			(layer "F.SilkS")
			(effects
				(font
					(size 0.7 0.7)
					(thickness 0.15)
				)
				(justify left bottom)
			)
		)
		(property "Value" "C_22p_0402"
			(at 0 1.4 0)
			(layer "F.Fab")
			(effects
				(font
					(size 0.7 0.7)
					(thickness 0.15)
				)
				(justify left bottom)
			)
		)
		(property "Description" " "
			(at 0 0 0)
			(layer "F.Fab")
			(hide yes)
			(effects
				(font
					(size 1.27 1.27)
					(thickness 0.15)
				)
			)
		)
		(property "Author" "Antmicro"
			(at 0 0 0)
			(layer "F.Fab")
			(hide yes)
			(effects
				(font
					(size 1 1)
					(thickness 0.15)
				)
			)
		)
		(property "Dielectric" ""
			(at 0 0 0)
			(layer "F.Fab")
			(hide yes)
			(effects
				(font
					(size 1 1)
					(thickness 0.15)
				)
			)
		)
		(property "License" "Apache-2.0"
			(at 0 0 0)
			(layer "F.Fab")
			(hide yes)
			(effects
				(font
					(size 1 1)
					(thickness 0.15)
				)
			)
		)
		(property "MPN" "CC0402JRNPO9BN220"
			(at 0 0 0)
			(layer "F.Fab")
			(hide yes)
			(effects
				(font
					(size 1 1)
					(thickness 0.15)
				)
			)
		)
		(property "Manufacturer" "Yaego"
			(at 0 0 0)
			(layer "F.Fab")
			(hide yes)
			(effects
				(font
					(size 1 1)
					(thickness 0.15)
				)
			)
		)
		(property "Val" "22p"
			(at 0 0 0)
			(layer "F.Fab")
			(hide yes)
			(effects
				(font
					(size 1 1)
					(thickness 0.15)
				)
			)
		)
		(property "Voltage" ""
			(at 0 0 0)
			(layer "F.Fab")
			(hide yes)
			(effects
				(font
					(size 1 1)
					(thickness 0.15)
				)
			)
		)
		(sheetname "Ethernet")
		(sheetfile "ethernet.kicad_sch")
		(attr smd)
		(fp_rect
			(start -0.94 -0.47)
			(end 0.94 0.47)
			(stroke
				(width 0.05)
				(type solid)
			)
			(fill no)
			(layer "F.CrtYd")
		)
		(fp_rect
			(start -0.499 -0.249)
			(end 0.499 0.249)
			(stroke
				(width 0.15)
				(type solid)
			)
			(fill no)
			(layer "F.Fab")
		)
		(pad "1" smd roundrect
			(at -0.484 0)
			(size 0.59 0.64)
			(layers "F.Cu" "F.Mask" "F.Paste")
			(roundrect_rratio 0.25)
			(net 657 "ETH_XI")
			(pintype "passive")
		)
		(pad "2" smd roundrect
			(at 0.484 0)
			(size 0.59 0.64)
			(layers "F.Cu" "F.Mask" "F.Paste")
			(roundrect_rratio 0.25)
			(net 5 "GND")
			(pintype "passive")
		)
	)
	(footprint "antmicro-footprints:FB_0603_1608Metric"
		(layer "F.Cu")
		(at 189.286328 101.174306 -90)
		(property "Reference" "FB5"
			(at 1.025694 0.786328 270)
			(layer "F.SilkS")
			(effects
				(font
					(size 0.7 0.7)
					(thickness 0.15)
				)
				(justify left bottom)
			)
		)
		(property "Value" "FB_120Z_2A_0603"
			(at 0 1.5 270)
			(layer "F.Fab")
			(effects
				(font
					(size 0.7 0.7)
					(thickness 0.15)
				)
				(justify left bottom)
			)
		)
		(property "Description" "Ferrite Beads WE-TMSB Suppression 240Ohm 200mA "
			(at 0 0 270)
			(layer "F.Fab")
			(hide yes)
			(effects
				(font
					(size 1.27 1.27)
					(thickness 0.15)
				)
			)
		)
		(property "Author" "Antmicro"
			(at 88.112022 290.460634 0)
			(layer "F.Fab")
			(hide yes)
			(effects
				(font
					(size 1 1)
					(thickness 0.15)
				)
			)
		)
		(property "License" "Apache-2.0"
			(at 88.112022 290.460634 0)
			(layer "F.Fab")
			(hide yes)
			(effects
				(font
					(size 1 1)
					(thickness 0.15)
				)
			)
		)
		(property "MPN" "BLM18PG121SN1D"
			(at 88.112022 290.460634 0)
			(layer "F.Fab")
			(hide yes)
			(effects
				(font
					(size 1 1)
					(thickness 0.15)
				)
			)
		)
		(property "Manufacturer" "Murata"
			(at 88.112022 290.460634 0)
			(layer "F.Fab")
			(hide yes)
			(effects
				(font
					(size 1 1)
					(thickness 0.15)
				)
			)
		)
		(sheetname "Ethernet")
		(sheetfile "ethernet.kicad_sch")
		(attr smd)
		(fp_line
			(start -0.196 0.406)
			(end 0.193 0.406)
			(stroke
				(width 0.15)
				(type solid)
			)
			(layer "F.SilkS")
		)
		(fp_line
			(start -0.196 -0.408)
			(end 0.193 -0.408)
			(stroke
				(width 0.15)
				(type solid)
			)
			(layer "F.SilkS")
		)
		(fp_rect
			(start -1.3 -0.6)
			(end 1.3 0.6)
			(stroke
				(width 0.05)
				(type solid)
			)
			(fill no)
			(layer "F.CrtYd")
		)
		(fp_line
			(start -0.803 0.406)
			(end -0.803 -0.408)
			(stroke
				(width 0.15)
				(type solid)
			)
			(layer "F.Fab")
		)
		(fp_line
			(start 0.8 0.406)
			(end -0.803 0.406)
			(stroke
				(width 0.15)
				(type solid)
			)
			(layer "F.Fab")
		)
		(fp_line
			(start 0.8 -0.408)
			(end 0.8 0.406)
			(stroke
				(width 0.15)
				(type solid)
			)
			(layer "F.Fab")
		)
		(fp_line
			(start 0.8 -0.408)
			(end -0.803 -0.408)
			(stroke
				(width 0.15)
				(type solid)
			)
			(layer "F.Fab")
		)
		(pad "1" smd roundrect
			(at -0.891 0 270)
			(size 0.762 1.09)
			(layers "F.Cu" "F.Mask" "F.Paste")
			(roundrect_rratio 0.15)
			(net 602 "1V2_SYS")
			(pintype "passive")
		)
		(pad "2" smd roundrect
			(at 0.888 0 270)
			(size 0.762 1.09)
			(layers "F.Cu" "F.Mask" "F.Paste")
			(roundrect_rratio 0.15)
			(net 530 "/Ethernet/AVDDL_PLL")
			(pintype "passive")
		)
	)
	(footprint "antmicro-footprints:R_0402_1005Metric"
		(layer "F.Cu")
		(at 193.586328 106.474306 90)
		(descr "Resistor SMD 0402")
		(tags "resistor SMD 0402")
		(property "Reference" "R72"
			(at -1.225694 1.313672 90)
			(layer "F.SilkS")
			(effects
				(font
					(size 0.7 0.7)
					(thickness 0.15)
				)
				(justify left bottom)
			)
		)
		(property "Value" "R_12k1_0402"
			(at 0 1.4 90)
			(layer "F.Fab")
			(effects
				(font
					(size 0.7 0.7)
					(thickness 0.15)
				)
				(justify left bottom)
			)
		)
		(property "Description" "12k1 resistor in 0402 package with 1% tolerance"
			(at 0 0 90)
			(layer "F.Fab")
			(hide yes)
			(effects
				(font
					(size 1.27 1.27)
					(thickness 0.15)
				)
			)
		)
		(property "Author" "Antmicro"
			(at 300.060634 -87.112022 0)
			(layer "F.Fab")
			(hide yes)
			(effects
				(font
					(size 1 1)
					(thickness 0.15)
				)
			)
		)
		(property "License" "Apache-2.0"
			(at 300.060634 -87.112022 0)
			(layer "F.Fab")
			(hide yes)
			(effects
				(font
					(size 1 1)
					(thickness 0.15)
				)
			)
		)
		(property "MPN" "CR0402-FX-1212GLF"
			(at 300.060634 -87.112022 0)
			(layer "F.Fab")
			(hide yes)
			(effects
				(font
					(size 1 1)
					(thickness 0.15)
				)
			)
		)
		(property "Manufacturer" "Bourns"
			(at 300.060634 -87.112022 0)
			(layer "F.Fab")
			(hide yes)
			(effects
				(font
					(size 1 1)
					(thickness 0.15)
				)
			)
		)
		(property "Tolerance" "1%"
			(at 300.060634 -87.112022 0)
			(layer "F.Fab")
			(hide yes)
			(effects
				(font
					(size 1 1)
					(thickness 0.15)
				)
			)
		)
		(property "Val" "12k1"
			(at 300.060634 -87.112022 0)
			(layer "F.Fab")
			(hide yes)
			(effects
				(font
					(size 1 1)
					(thickness 0.15)
				)
			)
		)
		(sheetname "Ethernet")
		(sheetfile "ethernet.kicad_sch")
		(attr smd)
		(fp_rect
			(start -0.93 -0.47)
			(end 0.93 0.47)
			(stroke
				(width 0.05)
				(type solid)
			)
			(fill no)
			(layer "F.CrtYd")
		)
		(fp_rect
			(start -0.5 -0.25)
			(end 0.5 0.25)
			(stroke
				(width 0.15)
				(type solid)
			)
			(fill no)
			(layer "F.Fab")
		)
		(pad "1" smd roundrect
			(at -0.485 0 90)
			(size 0.59 0.64)
			(layers "F.Cu" "F.Mask" "F.Paste")
			(roundrect_rratio 0.25)
			(net 5 "GND")
			(pintype "passive")
		)
		(pad "2" smd roundrect
			(at 0.485 0 90)
			(size 0.59 0.64)
			(layers "F.Cu" "F.Mask" "F.Paste")
			(roundrect_rratio 0.25)
			(net 261 "Net-(U6-ISET)")
			(pintype "passive")
		)
	)
)
